# BASEBOARD_FAB2 (Tioga Pass) — schematic netlist excerpt (pin names and nets, part order shuffled) for the footprints in the layout excerpt that follows; sources: Cadence DE-HDL packaged netlist, KiCad conversion of Wiwynn_Tioga_Pass_MB.brd

R4W5  RES  0.0 5% EMPTY  pkg 0402  page 102 : A = FM_DB1200_PWRGD ; B = FM_DB1200_PWRGD_R
C4C18  CAP  1.0UF 16V 10% X6S  pkg 0402  page 204 : A = VR_FET_SW_P12V_STBY_PVCCIN_CPU0 ; B = GND
TH7A1  MTG_KEYHOLE  EMPTY  pkg TH  page 195 : \1\ = GND

(kicad_pcb
	(version 20260206)
	(generator "pcbnew")
	(generator_version "10.0")
	(general
		(thickness 1.6)
		(legacy_teardrops no)
	)
	(paper "A4")
	(title_block
		(title "Wiwynn_Tioga_Pass_MB.brd")
		(comment 1 "Tioga Pass / footprints 879-881 of 4770")
	)
	(layers
		(0 "F.Cu" signal "TOP")
		(4 "In1.Cu" signal "L2GND")
		(6 "In2.Cu" signal "L3")
		(8 "In3.Cu" signal "L4GND")
		(10 "In4.Cu" signal "L5")
		(12 "In5.Cu" signal "L6GND")
		(14 "In6.Cu" signal "L7VCC")
		(16 "In7.Cu" signal "L8VCC")
		(18 "In8.Cu" signal "L9GND")
		(20 "In9.Cu" signal "L10")
		(22 "In10.Cu" signal "L11GND")
		(24 "In11.Cu" signal "L12")
		(26 "In12.Cu" signal "L13GND")
		(2 "B.Cu" signal "BOTTOM")
		(9 "F.Adhes" user "F.Adhesive")
		(11 "B.Adhes" user "B.Adhesive")
		(13 "F.Paste" user "Package Geometry/Pastemask Top")
		(15 "B.Paste" user "Package Geometry/Pastemask Bottom")
		(5 "F.SilkS" user "Ref Des/Silkscreen Top")
		(7 "B.SilkS" user "Ref Des/Silkscreen Bottom")
		(1 "F.Mask" user "Board Geometry/Soldermask Top")
		(3 "B.Mask" user "Board Geometry/Soldermask Bottom")
		(17 "Dwgs.User" user "User.Drawings")
		(19 "Cmts.User" user "User.Comments")
		(21 "Eco1.User" user "User.Eco1")
		(23 "Eco2.User" user "User.Eco2")
		(25 "Edge.Cuts" user "Board Geometry/Outline")
		(27 "Margin" user)
		(31 "F.CrtYd" user "Package Geometry/Place Bound Top")
		(29 "B.CrtYd" user "Package Geometry/Place Bound Bottom")
		(35 "F.Fab" user "Ref Des/Assembly Top")
		(33 "B.Fab" user "Ref Des/Assembly Bottom")
	)
	(footprint ""
		(layer "F.Cu")
		(at 168.07942 -73.662032 180)
		(property "Reference" "R4W5"
			(at -0.8382 -0.67818 180)
			(unlocked yes)
			(layer "F.SilkS")
			(effects
				(font
					(size 0.4064 0.254)
					(thickness 0.1524)
				)
				(justify left)
			)
		)
		(property "Value" ""
			(at 0 0 180)
			(layer "F.Fab")
			(effects
				(font
					(size 1.27 1.27)
				)
			)
		)
		(duplicate_pad_numbers_are_jumpers no)
		(fp_poly
			(pts
				(xy -0.2794 -0.1016) (xy 0.2794 -0.1016) (xy 0.2794 0.9906) (xy -0.2794 0.9906)
			)
			(stroke
				(width 0)
				(type default)
			)
			(fill no)
			(layer "F.CrtYd")
		)
		(fp_line
			(start 0.2794 0.9906)
			(end 0.2794 -0.1016)
			(stroke
				(width 0.1)
				(type default)
			)
			(layer "F.Fab")
		)
		(fp_line
			(start 0.2794 -0.1016)
			(end -0.2794 -0.1016)
			(stroke
				(width 0.1)
				(type default)
			)
			(layer "F.Fab")
		)
		(fp_line
			(start -0.2794 0.9906)
			(end 0.2794 0.9906)
			(stroke
				(width 0.1)
				(type default)
			)
			(layer "F.Fab")
		)
		(fp_line
			(start -0.2794 -0.1016)
			(end -0.2794 0.9906)
			(stroke
				(width 0.1)
				(type default)
			)
			(layer "F.Fab")
		)
		(pad "1" smd rect
			(at 0 0 180)
			(size 0.508 0.508)
			(layers "F.Cu" "F.Mask" "F.Paste")
			(net "FM_DB1200_PWRGD")
		)
		(pad "2" smd rect
			(at 0 0.889 180)
			(size 0.508 0.508)
			(layers "F.Cu" "F.Mask" "F.Paste")
			(net "FM_DB1200_PWRGD_R")
		)
		(zone
			(layer "F.Cu")
			(hatch none 0.5)
			(connect_pads
				(clearance 0)
			)
			(min_thickness 0.25)
			(keepout
				(tracks not_allowed)
				(vias allowed)
				(pads allowed)
				(copperpour not_allowed)
				(footprints allowed)
			)
			(placement
				(enabled no)
				(sheetname "")
			)
			(fill
				(thermal_gap 0.5)
				(thermal_bridge_width 0.5)
				(island_removal_mode 0)
			)
			(polygon
				(pts
					(xy 168.33342 -74.297032) (xy 167.82542 -74.297032) (xy 167.82542 -73.916032) (xy 168.33342 -73.916032)
				)
			)
		)
		(zone
			(layer "F.Cu")
			(hatch none 0.5)
			(connect_pads
				(clearance 0)
			)
			(min_thickness 0.25)
			(keepout
				(tracks allowed)
				(vias not_allowed)
				(pads allowed)
				(copperpour not_allowed)
				(footprints allowed)
			)
			(placement
				(enabled no)
				(sheetname "")
			)
			(fill
				(thermal_gap 0.5)
				(thermal_bridge_width 0.5)
				(island_removal_mode 0)
			)
			(polygon
				(pts
					(xy 168.33342 -73.916032) (xy 167.82542 -73.916032) (xy 167.82542 -74.297032) (xy 168.33342 -74.297032)
				)
			)
		)
	)
	(footprint ""
		(layer "F.Cu")
		(at 194.749928 -92.210382 -90)
		(property "Reference" "C4C18"
			(at 0 0 270)
			(layer "F.SilkS")
			(hide yes)
			(effects
				(font
					(size 1.27 1.27)
				)
			)
		)
		(property "Value" ""
			(at 0 0 270)
			(layer "F.Fab")
			(effects
				(font
					(size 1.27 1.27)
				)
			)
		)
		(duplicate_pad_numbers_are_jumpers no)
		(fp_poly
			(pts
				(xy 0.3048 -0.1016) (xy 0.3048 0.9906) (xy -0.3048 0.9906) (xy -0.3048 -0.1016)
			)
			(stroke
				(width 0)
				(type default)
			)
			(fill no)
			(layer "F.CrtYd")
		)
		(fp_line
			(start -0.3048 0.9906)
			(end 0.3048 0.9906)
			(stroke
				(width 0.1)
				(type default)
			)
			(layer "F.Fab")
		)
		(fp_line
			(start 0.3048 0.9906)
			(end 0.3048 -0.1016)
			(stroke
				(width 0.1)
				(type default)
			)
			(layer "F.Fab")
		)
		(fp_line
			(start -0.3048 -0.1016)
			(end -0.3048 0.9906)
			(stroke
				(width 0.1)
				(type default)
			)
			(layer "F.Fab")
		)
		(fp_line
			(start 0.3048 -0.1016)
			(end -0.3048 -0.1016)
			(stroke
				(width 0.1)
				(type default)
			)
			(layer "F.Fab")
		)
		(pad "1" smd rect
			(at 0 0 270)
			(size 0.508 0.508)
			(layers "F.Cu" "F.Mask" "F.Paste")
			(net "VR_FET_SW_P12V_STBY_PVCCIN_CPU0")
		)
		(pad "2" smd rect
			(at 0 0.889 270)
			(size 0.508 0.508)
			(layers "F.Cu" "F.Mask" "F.Paste")
			(net "GND")
		)
		(zone
			(layer "F.Cu")
			(hatch none 0.5)
			(connect_pads
				(clearance 0)
			)
			(min_thickness 0.25)
			(keepout
				(tracks not_allowed)
				(vias allowed)
				(pads allowed)
				(copperpour not_allowed)
				(footprints allowed)
			)
			(placement
				(enabled no)
				(sheetname "")
			)
			(fill
				(thermal_gap 0.5)
				(thermal_bridge_width 0.5)
				(island_removal_mode 0)
			)
			(polygon
				(pts
					(xy 194.114928 -92.464382) (xy 194.114928 -91.956382) (xy 194.495928 -91.956382) (xy 194.495928 -92.464382)
				)
			)
		)
		(zone
			(layer "F.Cu")
			(hatch none 0.5)
			(connect_pads
				(clearance 0)
			)
			(min_thickness 0.25)
			(keepout
				(tracks allowed)
				(vias not_allowed)
				(pads allowed)
				(copperpour not_allowed)
				(footprints allowed)
			)
			(placement
				(enabled no)
				(sheetname "")
			)
			(fill
				(thermal_gap 0.5)
				(thermal_bridge_width 0.5)
				(island_removal_mode 0)
			)
			(polygon
				(pts
					(xy 194.495928 -92.464382) (xy 194.495928 -91.956382) (xy 194.114928 -91.956382) (xy 194.114928 -92.464382)
				)
			)
		)
	)
	(footprint ""
		(layer "F.Cu")
		(at 357.000048 -155.10002 90)
		(property "Reference" "TH7A1"
			(at -4.27609 8.277352 0)
			(unlocked yes)
			(layer "F.SilkS")
			(effects
				(font
					(size 0.7874 0.5842)
					(thickness 0.1524)
				)
				(justify left)
			)
		)
		(property "Value" ""
			(at 0 0 90)
			(layer "F.Fab")
			(effects
				(font
					(size 1.27 1.27)
				)
			)
		)
		(duplicate_pad_numbers_are_jumpers no)
		(fp_poly
			(pts
				(arc
					(start 3.0226 0.68834)
					(mid 3.042235 0.827855)
					(end 3.099562 0.956564)
				)
				(arc
					(start 3.099562 0.956564)
					(mid 4.012804 3.550073)
					(end 3.042158 6.12267)
				)
				(arc
					(start 3.042158 6.12267)
					(mid 0 7.518589)
					(end -3.042158 6.12267)
				)
				(arc
					(start -3.042158 6.12267)
					(mid -4.012854 3.55061)
					(end -3.100324 0.957326)
				)
				(arc
					(start -3.100324 0.957326)
					(mid -3.042498 0.827518)
					(end -3.0226 0.686816)
				)
				(arc
					(start -3.0226 -0.000254)
					(mid -2.137121 -2.137227)
					(end 0 -3.022346)
				)
				(arc
					(start 0 -3.022346)
					(mid 2.137227 -2.136973)
					(end 3.0226 0.000254)
				)
			)
			(stroke
				(width 0)
				(type default)
			)
			(fill no)
			(layer "F.CrtYd")
		)
		(pad "1" thru_hole custom
			(at 0 0 90)
			(size 2.00667 2.00667)
			(drill 0.3048)
			(layers "*.Cu" "*.Mask")
			(remove_unused_layers no)
			(net "GND")
			(clearance -0.889)
			(options
				(clearance outline)
				(anchor circle)
			)
			(primitives
				(gr_poly
					(pts
						(arc
							(start 3.042158 3.874516)
							(mid 0 5.270435)
							(end -3.042158 3.874516)
						)
						(arc
							(start -3.042158 3.874516)
							(mid -4.012854 1.302456)
							(end -3.100324 -1.290828)
						)
						(arc
							(start -3.100324 -1.290828)
							(mid -3.042498 -1.420636)
							(end -3.0226 -1.561338)
						)
						(arc
							(start -3.0226 -2.248408)
							(mid -2.137121 -4.385381)
							(end 0 -5.2705)
						)
						(arc
							(start 0 -5.2705)
							(mid 2.137227 -4.385127)
							(end 3.0226 -2.2479)
						)
						(arc
							(start 3.0226 -1.55956)
							(mid 3.04227 -1.420177)
							(end 3.099562 -1.29159)
						)
						(arc
							(start 3.099562 -1.29159)
							(mid 4.012804 1.301919)
							(end 3.042158 3.874516)
						)
					)
					(width 0)
					(fill yes)
				)
			)
		)
	)
)
